# T6G (Grand Teton) — schematic netlist excerpt (pin names and nets, part order shuffled) for the footprints in the layout excerpt that follows; sources: Cadence DE-HDL packaged netlist, KiCad conversion of 04192023_DAF0TMB3IC0_F0TG_MB_C_brd_V02_OCP.brd

PC6628  Q_CAPP  470UF 2.5V 20% SPCAP  pkg SMLF  page 365 : A = P0V9_CPU1_RT_2D ; B = GND
R835  Q_RES  1K 1% CHIP  pkg 0201LF  page 185 : A = P1V8_CPU0_RT_1D ; B = SMB_RT_CPU0_P0_ROM_R_SCL
C6623  Q_CAP_DIFFBUS  DIFF BUS_0.22UF 6.3V 20% X6S  pkg C0201  page 308 : \1\ = P5E_CPU0_P3_TX_BUF_C_DP<13> ; \2\ = P5E_CPU0_P3_TX_BUF_DP<13>
PC283_1  Q_CAP  22UF 4V 20% X6S  pkg C0805  page 211 : A = PVDDCR_CPU0_P1 ; B = GND

(kicad_pcb
	(version 20260206)
	(generator "pcbnew")
	(generator_version "10.0")
	(general
		(thickness 1.6)
		(legacy_teardrops no)
	)
	(paper "A4")
	(title_block
		(title "04192023_DAF0TMB3IC0_F0TG_MB_C_brd_V02_OCP.brd")
		(comment 1 "Grand Teton / footprints 5877-5880 of 8354")
	)
	(layers
		(0 "F.Cu" signal "TOP")
		(4 "In1.Cu" signal "GND")
		(6 "In2.Cu" signal "IN1")
		(8 "In3.Cu" signal "GND1")
		(10 "In4.Cu" signal "IN2")
		(12 "In5.Cu" signal "GND2")
		(14 "In6.Cu" signal "IN3")
		(16 "In7.Cu" signal "GND3")
		(18 "In8.Cu" signal "VCC")
		(20 "In9.Cu" signal "VCC1")
		(22 "In10.Cu" signal "GND4")
		(24 "In11.Cu" signal "IN4")
		(26 "In12.Cu" signal "GND5")
		(28 "In13.Cu" signal "IN5")
		(30 "In14.Cu" signal "GND6")
		(32 "In15.Cu" signal "IN6")
		(34 "In16.Cu" signal "GND7")
		(2 "B.Cu" signal "BOTTOM")
		(9 "F.Adhes" user "F.Adhesive")
		(11 "B.Adhes" user "B.Adhesive")
		(13 "F.Paste" user "Package Geometry/Pastemask Top")
		(15 "B.Paste" user "Package Geometry/Pastemask Bottom")
		(5 "F.SilkS" user "Ref Des/Silkscreen Top")
		(7 "B.SilkS" user "Ref Des/Silkscreen Bottom")
		(1 "F.Mask" user "Board Geometry/Soldermask Top")
		(3 "B.Mask" user "Board Geometry/Soldermask Bottom")
		(17 "Dwgs.User" user "User.Drawings")
		(19 "Cmts.User" user "User.Comments")
		(21 "Eco1.User" user "User.Eco1")
		(23 "Eco2.User" user "User.Eco2")
		(25 "Edge.Cuts" user "Board Geometry/Outline")
		(27 "Margin" user)
		(31 "F.CrtYd" user "Package Geometry/Place Bound Top")
		(29 "B.CrtYd" user "Package Geometry/Place Bound Bottom")
		(35 "F.Fab" user "Ref Des/Assembly Top")
		(33 "B.Fab" user "Ref Des/Assembly Bottom")
	)
	(footprint ""
		(layer "B.Cu")
		(at 295.402 -426.339 180)
		(property "Reference" "R835"
			(at 0 0 0)
			(layer "B.SilkS")
			(hide yes)
			(effects
				(font
					(size 1.27 1.27)
				)
				(justify mirror)
			)
		)
		(property "Value" ""
			(at 0 0 0)
			(layer "B.Fab")
			(effects
				(font
					(size 1.27 1.27)
				)
				(justify mirror)
			)
		)
		(duplicate_pad_numbers_are_jumpers no)
		(fp_line
			(start 0.32512 0.175006)
			(end 0.32512 -0.175006)
			(stroke
				(width 0.1)
				(type default)
			)
			(layer "B.Fab")
		)
		(fp_line
			(start 0.32512 -0.175006)
			(end -0.32512 -0.175006)
			(stroke
				(width 0.1)
				(type default)
			)
			(layer "B.Fab")
		)
		(fp_line
			(start -0.32512 0.175006)
			(end 0.32512 0.175006)
			(stroke
				(width 0.1)
				(type default)
			)
			(layer "B.Fab")
		)
		(fp_line
			(start -0.32512 -0.175006)
			(end -0.32512 0.175006)
			(stroke
				(width 0.1)
				(type default)
			)
			(layer "B.Fab")
		)
		(pad "1" smd rect
			(at 0.2667 0)
			(size 0.3048 0.381)
			(layers "B.Cu" "B.Mask" "B.Paste")
			(net "P1V8_CPU0_RT_1D")
		)
		(pad "2" smd rect
			(at -0.2667 0 180)
			(size 0.3048 0.381)
			(layers "B.Cu" "B.Mask" "B.Paste")
			(net "SMB_RT_CPU0_P0_ROM_R_SCL")
		)
	)
	(footprint ""
		(layer "B.Cu")
		(at 413.136842 -416.899344 90)
		(property "Reference" "C6623"
			(at 0 0 90)
			(layer "B.SilkS")
			(hide yes)
			(effects
				(font
					(size 1.27 1.27)
				)
				(justify mirror)
			)
		)
		(property "Value" ""
			(at 0 0 90)
			(layer "B.Fab")
			(effects
				(font
					(size 1.27 1.27)
				)
				(justify mirror)
			)
		)
		(duplicate_pad_numbers_are_jumpers no)
		(fp_line
			(start 0.299974 -0.150114)
			(end -0.299974 -0.150114)
			(stroke
				(width 0.1)
				(type default)
			)
			(layer "B.Fab")
		)
		(fp_line
			(start -0.299974 -0.150114)
			(end -0.299974 0.150114)
			(stroke
				(width 0.1)
				(type default)
			)
			(layer "B.Fab")
		)
		(fp_line
			(start 0.299974 0.150114)
			(end 0.299974 -0.150114)
			(stroke
				(width 0.1)
				(type default)
			)
			(layer "B.Fab")
		)
		(fp_line
			(start -0.299974 0.150114)
			(end 0.299974 0.150114)
			(stroke
				(width 0.1)
				(type default)
			)
			(layer "B.Fab")
		)
		(pad "1" smd rect
			(at 0.2667 0 270)
			(size 0.3048 0.381)
			(layers "B.Cu" "B.Mask" "B.Paste")
			(net "P5E_CPU0_P3_TX_BUF_C_DP<13>")
		)
		(pad "2" smd rect
			(at -0.2667 0 270)
			(size 0.3048 0.381)
			(layers "B.Cu" "B.Mask" "B.Paste")
			(net "P5E_CPU0_P3_TX_BUF_DP<13>")
		)
	)
	(footprint ""
		(layer "B.Cu")
		(at 86.652354 -191.358012 90)
		(property "Reference" "PC283_1"
			(at 0 0 90)
			(layer "B.SilkS")
			(hide yes)
			(effects
				(font
					(size 1.27 1.27)
				)
				(justify mirror)
			)
		)
		(property "Value" ""
			(at 0 0 90)
			(layer "B.Fab")
			(effects
				(font
					(size 1.27 1.27)
				)
				(justify mirror)
			)
		)
		(duplicate_pad_numbers_are_jumpers no)
		(fp_line
			(start 1.524 -0.762)
			(end -1.524 -0.762)
			(stroke
				(width 0.1524)
				(type default)
			)
			(layer "B.SilkS")
		)
		(fp_line
			(start -1.524 -0.762)
			(end -1.524 0.762)
			(stroke
				(width 0.1524)
				(type default)
			)
			(layer "B.SilkS")
		)
		(fp_line
			(start 1.524 0.762)
			(end 1.524 -0.762)
			(stroke
				(width 0.1524)
				(type default)
			)
			(layer "B.SilkS")
		)
		(fp_line
			(start -1.524 0.762)
			(end 1.524 0.762)
			(stroke
				(width 0.1524)
				(type default)
			)
			(layer "B.SilkS")
		)
		(fp_line
			(start 1.1049 -0.724916)
			(end 1.1049 0.724916)
			(stroke
				(width 0.1)
				(type default)
			)
			(layer "B.Fab")
		)
		(fp_line
			(start -1.1049 -0.724916)
			(end 1.1049 -0.724916)
			(stroke
				(width 0.1)
				(type default)
			)
			(layer "B.Fab")
		)
		(fp_line
			(start 1.1049 0.724916)
			(end -1.1049 0.724916)
			(stroke
				(width 0.1)
				(type default)
			)
			(layer "B.Fab")
		)
		(fp_line
			(start -1.1049 0.724916)
			(end -1.1049 -0.724916)
			(stroke
				(width 0.1)
				(type default)
			)
			(layer "B.Fab")
		)
		(pad "1" smd rect
			(at 0.889 0 90)
			(size 1.016 1.27)
			(layers "B.Cu" "B.Mask" "B.Paste")
			(net "PVDDCR_CPU0_P1")
		)
		(pad "2" smd rect
			(at -0.889 0 90)
			(size 1.016 1.27)
			(layers "B.Cu" "B.Mask" "B.Paste")
			(net "GND")
		)
	)
	(footprint ""
		(layer "B.Cu")
		(at 6.649974 -373.339614 90)
		(property "Reference" "PC6628"
			(at -3.388614 -2.993644 270)
			(unlocked yes)
			(layer "B.SilkS")
			(effects
				(font
					(size 0.7874 0.5842)
					(thickness 0.1524)
				)
				(justify left mirror)
			)
		)
		(property "Value" ""
			(at 0 0 90)
			(layer "B.Fab")
			(effects
				(font
					(size 1.27 1.27)
				)
				(justify mirror)
			)
		)
		(duplicate_pad_numbers_are_jumpers no)
		(fp_line
			(start 4.84378 -2.150618)
			(end 4.53898 -2.150618)
			(stroke
				(width 0.1524)
				(type default)
			)
			(layer "B.SilkS")
		)
		(fp_line
			(start 4.84378 -2.150618)
			(end 4.842256 2.163064)
			(stroke
				(width 0.1524)
				(type default)
			)
			(layer "B.SilkS")
		)
		(fp_line
			(start 4.69138 -2.150618)
			(end 4.692396 2.161032)
			(stroke
				(width 0.1524)
				(type default)
			)
			(layer "B.SilkS")
		)
		(fp_line
			(start 4.53898 -2.150618)
			(end 4.539742 2.152142)
			(stroke
				(width 0.1524)
				(type default)
			)
			(layer "B.SilkS")
		)
		(fp_line
			(start 4.53898 -2.15011)
			(end -3.820414 -2.15011)
			(stroke
				(width 0.1524)
				(type default)
			)
			(layer "B.SilkS")
		)
		(fp_line
			(start -4.53898 -1.950974)
			(end -4.53898 2.15011)
			(stroke
				(width 0.1524)
				(type default)
			)
			(layer "B.SilkS")
		)
		(fp_line
			(start 4.53898 2.15011)
			(end 4.53898 -2.15011)
			(stroke
				(width 0.1524)
				(type default)
			)
			(layer "B.SilkS")
		)
		(fp_line
			(start -4.53898 2.15011)
			(end 4.53898 2.15011)
			(stroke
				(width 0.1524)
				(type default)
			)
			(layer "B.SilkS")
		)
		(fp_line
			(start 4.83108 2.150364)
			(end 4.447794 2.149348)
			(stroke
				(width 0.1524)
				(type default)
			)
			(layer "B.SilkS")
		)
		(fp_line
			(start 3.64998 -2.15011)
			(end -3.64998 -2.15011)
			(stroke
				(width 0.1)
				(type default)
			)
			(layer "B.Fab")
		)
		(fp_line
			(start -3.64998 -2.15011)
			(end -3.64998 2.15011)
			(stroke
				(width 0.1)
				(type default)
			)
			(layer "B.Fab")
		)
		(fp_line
			(start 3.64998 2.15011)
			(end 3.64998 -2.15011)
			(stroke
				(width 0.1)
				(type default)
			)
			(layer "B.Fab")
		)
		(fp_line
			(start -3.64998 2.15011)
			(end 3.64998 2.15011)
			(stroke
				(width 0.1)
				(type default)
			)
			(layer "B.Fab")
		)
		(fp_text user "-"
			(at -4.404614 -1.919224 90)
			(unlocked yes)
			(layer "B.SilkS")
			(effects
				(font
					(size 1.905 1.4224)
					(thickness 0.1524)
				)
				(justify left mirror)
			)
		)
		(fp_text user "+"
			(at 6.214872 -0.337058 90)
			(unlocked yes)
			(layer "B.SilkS")
			(effects
				(font
					(size 1.905 1.4224)
					(thickness 0.1524)
				)
				(justify left mirror)
			)
		)
		(fp_text user "+"
			(at 6.214872 -0.337058 90)
			(unlocked yes)
			(layer "B.Fab")
			(effects
				(font
					(size 1.905 1.4224)
					(thickness 0.1524)
				)
				(justify left mirror)
			)
		)
		(fp_text user "-"
			(at -4.313174 -0.094488 90)
			(unlocked yes)
			(layer "B.Fab")
			(effects
				(font
					(size 1.905 1.4224)
					(thickness 0.1524)
				)
				(justify left mirror)
			)
		)
		(pad "1" smd rect
			(at 3.199892 0 270)
			(size 2.413 2.8194)
			(layers "B.Cu" "B.Mask" "B.Paste")
			(net "P0V9_CPU1_RT_2D")
		)
		(pad "2" smd rect
			(at -3.199892 0 270)
			(size 2.413 2.8194)
			(layers "B.Cu" "B.Mask" "B.Paste")
			(net "GND")
		)
	)
)
